(kicad_pcb
	(version 20241229)
	(generator "pcbnew")
	(generator_version "9.0")
	(general
		(thickness 1.294)
		(legacy_teardrops no)
	)
	(paper "A3")
	(title_block
		(title "Kintex 410T devboard")
		(date "2024-04-03")
		(rev "1.1.2")
		(comment 9 "footprints 638-643 of 975")
	)
	(layers
		(0 "F.Cu" mixed)
		(4 "In1.Cu" power)
		(6 "In2.Cu" power)
		(8 "In3.Cu" mixed)
		(10 "In4.Cu" power)
		(12 "In5.Cu" mixed)
		(14 "In6.Cu" power)
		(16 "In7.Cu" mixed)
		(18 "In8.Cu" power)
		(2 "B.Cu" mixed)
		(9 "F.Adhes" user "F.Adhesive")
		(11 "B.Adhes" user "B.Adhesive")
		(13 "F.Paste" user)
		(15 "B.Paste" user)
		(5 "F.SilkS" user "F.Silkscreen")
		(7 "B.SilkS" user "B.Silkscreen")
		(1 "F.Mask" user)
		(3 "B.Mask" user)
		(17 "Dwgs.User" user "User.Drawings")
		(19 "Cmts.User" user "User.Comments")
		(21 "Eco1.User" user "User.Eco1")
		(23 "Eco2.User" user "User.Eco2")
		(25 "Edge.Cuts" user)
		(27 "Margin" user)
		(31 "F.CrtYd" user "F.Courtyard")
		(29 "B.CrtYd" user "B.Courtyard")
		(35 "F.Fab" user)
		(33 "B.Fab" user)
	)
	(footprint "antmicro-footprints:R_Array_4x0201_Panasonic_EXB18V"
		(layer "B.Cu")
		(at 253.901 127.9)
		(property "Reference" "R23"
			(at 1.174 -0.725 0)
			(layer "B.SilkS")
			(effects
				(font
					(size 0.7 0.7)
					(thickness 0.15)
				)
				(justify left bottom mirror)
			)
		)
		(property "Value" "R_4x33R_0201_array"
			(at -1.1 -1.8 0)
			(layer "B.Fab")
			(effects
				(font
					(size 0.7 0.7)
					(thickness 0.15)
				)
				(justify right bottom mirror)
			)
		)
		(property "Description" "Fixed Network Resistor, 33 ohm, Isolated, 4 Resistors, 0502 [1406 Metric], Flat, ± 5%"
			(at 0 0 0)
			(layer "F.Fab")
			(hide yes)
			(effects
				(font
					(size 1.27 1.27)
					(thickness 0.15)
				)
			)
		)
		(property "Author" "Antmicro"
			(at 0 0 0)
			(layer "B.Fab")
			(hide yes)
			(effects
				(font
					(size 1 1)
					(thickness 0.15)
				)
				(justify mirror)
			)
		)
		(property "License" "Apache-2.0"
			(at 0 0 0)
			(layer "B.Fab")
			(hide yes)
			(effects
				(font
					(size 1 1)
					(thickness 0.15)
				)
				(justify mirror)
			)
		)
		(property "MPN" "EXB-18V330JX"
			(at 0 0 0)
			(layer "B.Fab")
			(hide yes)
			(effects
				(font
					(size 1 1)
					(thickness 0.15)
				)
				(justify mirror)
			)
		)
		(property "Manufacturer" "Panasonic"
			(at 0 0 0)
			(layer "B.Fab")
			(hide yes)
			(effects
				(font
					(size 1 1)
					(thickness 0.15)
				)
				(justify mirror)
			)
		)
		(property "Val" "R_4x33R_0201"
			(at 0 0 0)
			(layer "B.Fab")
			(hide yes)
			(effects
				(font
					(size 1 1)
					(thickness 0.15)
				)
				(justify mirror)
			)
		)
		(sheetname "Supervisior MCU")
		(sheetfile "supervisor-mcu.kicad_sch")
		(attr smd)
		(fp_line
			(start -0.8 0.45)
			(end -0.8 -0.45)
			(stroke
				(width 0.12)
				(type solid)
			)
			(layer "B.SilkS")
		)
		(fp_line
			(start 0.8 0.45)
			(end 0.8 -0.45)
			(stroke
				(width 0.12)
				(type solid)
			)
			(layer "B.SilkS")
		)
		(fp_rect
			(start -0.898 0.66)
			(end 0.898 -0.65)
			(stroke
				(width 0.05)
				(type solid)
			)
			(fill no)
			(layer "B.CrtYd")
		)
		(pad "1" smd roundrect
			(at -0.6 -0.298)
			(size 0.2 0.4)
			(layers "B.Cu" "B.Mask" "B.Paste")
			(roundrect_rratio 0.25)
			(net 1359 "/SUP_MCU.A5")
			(pinfunction "R1.1")
			(pintype "passive")
		)
		(pad "2" smd roundrect
			(at -0.202 -0.298)
			(size 0.2 0.4)
			(layers "B.Cu" "B.Mask" "B.Paste")
			(roundrect_rratio 0.25)
			(net 1360 "/SUP_MCU.A3")
			(pinfunction "R2.1")
			(pintype "passive")
		)
		(pad "3" smd roundrect
			(at 0.2 -0.298)
			(size 0.2 0.4)
			(layers "B.Cu" "B.Mask" "B.Paste")
			(roundrect_rratio 0.25)
			(net 1337 "/SUP_MCU.SDA")
			(pinfunction "R3.1")
			(pintype "passive")
		)
		(pad "4" smd roundrect
			(at 0.598 -0.298)
			(size 0.2 0.4)
			(layers "B.Cu" "B.Mask" "B.Paste")
			(roundrect_rratio 0.25)
			(net 1361 "/SUP_MCU.A4")
			(pinfunction "R4.1")
			(pintype "passive")
		)
		(pad "5" smd roundrect
			(at 0.598 0.3)
			(size 0.2 0.4)
			(layers "B.Cu" "B.Mask" "B.Paste")
			(roundrect_rratio 0.25)
			(net 1065 "/Supervisior MCU/USB_A4")
			(pinfunction "R4.2")
			(pintype "passive")
		)
		(pad "6" smd roundrect
			(at 0.2 0.3)
			(size 0.2 0.4)
			(layers "B.Cu" "B.Mask" "B.Paste")
			(roundrect_rratio 0.25)
			(net 1101 "/Supervisior MCU/SDA0")
			(pinfunction "R3.2")
			(pintype "passive")
		)
		(pad "7" smd roundrect
			(at -0.202 0.3)
			(size 0.2 0.4)
			(layers "B.Cu" "B.Mask" "B.Paste")
			(roundrect_rratio 0.25)
			(net 1064 "/Supervisior MCU/USB_A3")
			(pinfunction "R2.2")
			(pintype "passive")
		)
		(pad "8" smd roundrect
			(at -0.6 0.3)
			(size 0.2 0.4)
			(layers "B.Cu" "B.Mask" "B.Paste")
			(roundrect_rratio 0.25)
			(net 1066 "/Supervisior MCU/USB_A5")
			(pinfunction "R1.2")
			(pintype "passive")
		)
	)
	(footprint "antmicro-footprints:R_0402_1005Metric"
		(layer "B.Cu")
		(at 159.515001 82.635001)
		(descr "Resistor SMD 0402")
		(tags "resistor SMD 0402")
		(property "Reference" "R275"
			(at -0.765001 0.389999 180)
			(layer "B.SilkS")
			(effects
				(font
					(size 0.7 0.7)
					(thickness 0.15)
				)
				(justify left bottom mirror)
			)
		)
		(property "Value" "R_33R_0402"
			(at 0 -1.4 180)
			(layer "B.Fab")
			(effects
				(font
					(size 0.7 0.7)
					(thickness 0.15)
				)
				(justify left bottom mirror)
			)
		)
		(property "Description" "SMD Chip Resistor, 33 ohm, ± 1%, 62.5 mW, 0402 [1005 Metric], Thick Film, General Purpose"
			(at 0 0 0)
			(layer "F.Fab")
			(hide yes)
			(effects
				(font
					(size 1.27 1.27)
					(thickness 0.15)
				)
			)
		)
		(property "Author" "Antmicro"
			(at 0 0 0)
			(layer "B.Fab")
			(hide yes)
			(effects
				(font
					(size 1 1)
					(thickness 0.15)
				)
				(justify mirror)
			)
		)
		(property "License" "Apache-2.0"
			(at 0 0 0)
			(layer "B.Fab")
			(hide yes)
			(effects
				(font
					(size 1 1)
					(thickness 0.15)
				)
				(justify mirror)
			)
		)
		(property "MPN" "CR0402-FX-33R0GLF"
			(at 0 0 0)
			(layer "B.Fab")
			(hide yes)
			(effects
				(font
					(size 1 1)
					(thickness 0.15)
				)
				(justify mirror)
			)
		)
		(property "Manufacturer" "Bourns"
			(at 0 0 0)
			(layer "B.Fab")
			(hide yes)
			(effects
				(font
					(size 1 1)
					(thickness 0.15)
				)
				(justify mirror)
			)
		)
		(property "Tolerance" "1%"
			(at 0 0 0)
			(layer "B.Fab")
			(hide yes)
			(effects
				(font
					(size 1 1)
					(thickness 0.15)
				)
				(justify mirror)
			)
		)
		(property "Val" "33R"
			(at 0 0 0)
			(layer "B.Fab")
			(hide yes)
			(effects
				(font
					(size 1 1)
					(thickness 0.15)
				)
				(justify mirror)
			)
		)
		(sheetname "FMC+ HSPC")
		(sheetfile "fmc-hspc.kicad_sch")
		(attr smd)
		(fp_rect
			(start -0.925 0.47)
			(end 0.925 -0.47)
			(stroke
				(width 0.05)
				(type default)
			)
			(fill no)
			(layer "B.CrtYd")
		)
		(fp_rect
			(start -0.5 0.25)
			(end 0.5 -0.25)
			(stroke
				(width 0.15)
				(type solid)
			)
			(fill no)
			(layer "B.Fab")
		)
		(pad "1" smd roundrect
			(at -0.48 0)
			(size 0.59 0.64)
			(layers "B.Cu" "B.Mask" "B.Paste")
			(roundrect_rratio 0.25)
			(net 597 "/FMC+ HSPC/GTR_REFCLK3_R_P")
			(pintype "passive")
		)
		(pad "2" smd roundrect
			(at 0.48 0)
			(size 0.59 0.64)
			(layers "B.Cu" "B.Mask" "B.Paste")
			(roundrect_rratio 0.25)
			(net 598 "/FMC+ HSPC/GTX116.REFCLK1_P")
			(pintype "passive")
		)
	)
	(footprint "antmicro-footprints:R_0402_1005Metric"
		(layer "B.Cu")
		(at 245.299999 84.599999 -90)
		(descr "Resistor SMD 0402")
		(tags "resistor SMD 0402")
		(property "Reference" "R119"
			(at 0.800001 -0.450001 90)
			(layer "B.SilkS")
			(effects
				(font
					(size 0.7 0.7)
					(thickness 0.15)
				)
				(justify left bottom mirror)
			)
		)
		(property "Value" "R_100R_0402"
			(at 0 -1.4 90)
			(layer "B.Fab")
			(effects
				(font
					(size 0.7 0.7)
					(thickness 0.15)
				)
				(justify left bottom mirror)
			)
		)
		(property "Description" "SMD Chip Resistor, 100 ohm, ± 1%, 62.5 mW, 0402 [1005 Metric], Thick Film, General Purpose"
			(at 0 0 270)
			(layer "F.Fab")
			(hide yes)
			(effects
				(font
					(size 1.27 1.27)
					(thickness 0.15)
				)
			)
		)
		(property "Author" "Antmicro"
			(at 160.7 329.899998 0)
			(layer "B.Fab")
			(hide yes)
			(effects
				(font
					(size 1 1)
					(thickness 0.15)
				)
				(justify mirror)
			)
		)
		(property "License" "Apache-2.0"
			(at 160.7 329.899998 0)
			(layer "B.Fab")
			(hide yes)
			(effects
				(font
					(size 1 1)
					(thickness 0.15)
				)
				(justify mirror)
			)
		)
		(property "MPN" "CR0402-FX-1000GLF"
			(at 160.7 329.899998 0)
			(layer "B.Fab")
			(hide yes)
			(effects
				(font
					(size 1 1)
					(thickness 0.15)
				)
				(justify mirror)
			)
		)
		(property "Manufacturer" "Bourns"
			(at 160.7 329.899998 0)
			(layer "B.Fab")
			(hide yes)
			(effects
				(font
					(size 1 1)
					(thickness 0.15)
				)
				(justify mirror)
			)
		)
		(property "Tolerance" "1%"
			(at 160.7 329.899998 0)
			(layer "B.Fab")
			(hide yes)
			(effects
				(font
					(size 1 1)
					(thickness 0.15)
				)
				(justify mirror)
			)
		)
		(property "Val" "100R"
			(at 160.7 329.899998 0)
			(layer "B.Fab")
			(hide yes)
			(effects
				(font
					(size 1 1)
					(thickness 0.15)
				)
				(justify mirror)
			)
		)
		(sheetname "User GPIO + LED + button + DIP switch")
		(sheetfile "user-gpio.kicad_sch")
		(attr smd)
		(fp_rect
			(start -0.925 0.47)
			(end 0.925 -0.47)
			(stroke
				(width 0.05)
				(type default)
			)
			(fill no)
			(layer "B.CrtYd")
		)
		(fp_rect
			(start -0.5 0.25)
			(end 0.5 -0.25)
			(stroke
				(width 0.15)
				(type solid)
			)
			(fill no)
			(layer "B.Fab")
		)
		(pad "1" smd roundrect
			(at -0.48 0 270)
			(size 0.59 0.64)
			(layers "B.Cu" "B.Mask" "B.Paste")
			(roundrect_rratio 0.25)
			(net 810 "/User GPIO + LED + button + DIP switch/PMOD_B_10")
			(pintype "passive")
		)
		(pad "2" smd roundrect
			(at 0.48 0 270)
			(size 0.59 0.64)
			(layers "B.Cu" "B.Mask" "B.Paste")
			(roundrect_rratio 0.25)
			(net 453 "/FPGA Bank 12 & 13/PMOD_B.IO10")
			(pintype "passive")
		)
	)
	(footprint "antmicro-footprints:R_0402_1005Metric"
		(layer "B.Cu")
		(at 215.499999 77.899999 90)
		(descr "Resistor SMD 0402")
		(tags "resistor SMD 0402")
		(property "Reference" "R113"
			(at 3.599999 0.350001 270)
			(layer "B.SilkS")
			(effects
				(font
					(size 0.7 0.7)
					(thickness 0.15)
				)
				(justify left bottom mirror)
			)
		)
		(property "Value" "R_100R_0402"
			(at 0 -1.4 270)
			(layer "B.Fab")
			(effects
				(font
					(size 0.7 0.7)
					(thickness 0.15)
				)
				(justify left bottom mirror)
			)
		)
		(property "Description" "SMD Chip Resistor, 100 ohm, ± 1%, 62.5 mW, 0402 [1005 Metric], Thick Film, General Purpose"
			(at 0 0 90)
			(layer "F.Fab")
			(hide yes)
			(effects
				(font
					(size 1.27 1.27)
					(thickness 0.15)
				)
			)
		)
		(property "Author" "Antmicro"
			(at 293.399998 -137.6 0)
			(layer "B.Fab")
			(hide yes)
			(effects
				(font
					(size 1 1)
					(thickness 0.15)
				)
				(justify mirror)
			)
		)
		(property "License" "Apache-2.0"
			(at 293.399998 -137.6 0)
			(layer "B.Fab")
			(hide yes)
			(effects
				(font
					(size 1 1)
					(thickness 0.15)
				)
				(justify mirror)
			)
		)
		(property "MPN" "CR0402-FX-1000GLF"
			(at 293.399998 -137.6 0)
			(layer "B.Fab")
			(hide yes)
			(effects
				(font
					(size 1 1)
					(thickness 0.15)
				)
				(justify mirror)
			)
		)
		(property "Manufacturer" "Bourns"
			(at 293.399998 -137.6 0)
			(layer "B.Fab")
			(hide yes)
			(effects
				(font
					(size 1 1)
					(thickness 0.15)
				)
				(justify mirror)
			)
		)
		(property "Tolerance" "1%"
			(at 293.399998 -137.6 0)
			(layer "B.Fab")
			(hide yes)
			(effects
				(font
					(size 1 1)
					(thickness 0.15)
				)
				(justify mirror)
			)
		)
		(property "Val" "100R"
			(at 293.399998 -137.6 0)
			(layer "B.Fab")
			(hide yes)
			(effects
				(font
					(size 1 1)
					(thickness 0.15)
				)
				(justify mirror)
			)
		)
		(sheetname "User GPIO + LED + button + DIP switch")
		(sheetfile "user-gpio.kicad_sch")
		(attr smd)
		(fp_rect
			(start -0.925 0.47)
			(end 0.925 -0.47)
			(stroke
				(width 0.05)
				(type default)
			)
			(fill no)
			(layer "B.CrtYd")
		)
		(fp_rect
			(start -0.5 0.25)
			(end 0.5 -0.25)
			(stroke
				(width 0.15)
				(type solid)
			)
			(fill no)
			(layer "B.Fab")
		)
		(pad "1" smd roundrect
			(at -0.48 0 90)
			(size 0.59 0.64)
			(layers "B.Cu" "B.Mask" "B.Paste")
			(roundrect_rratio 0.25)
			(net 806 "/User GPIO + LED + button + DIP switch/PMOD_A_8")
			(pintype "passive")
		)
		(pad "2" smd roundrect
			(at 0.48 0 90)
			(size 0.59 0.64)
			(layers "B.Cu" "B.Mask" "B.Paste")
			(roundrect_rratio 0.25)
			(net 434 "/FPGA Bank 12 & 13/PMOD_A.IO8")
			(pintype "passive")
		)
	)
	(footprint "antmicro-footprints:R_0402_1005Metric"
		(layer "B.Cu")
		(at 198.491252 95.55)
		(descr "Resistor SMD 0402")
		(tags "resistor SMD 0402")
		(property "Reference" "R217"
			(at 1.483748 -4.6 180)
			(layer "B.SilkS")
			(effects
				(font
					(size 0.7 0.7)
					(thickness 0.15)
				)
				(justify left bottom mirror)
			)
		)
		(property "Value" "R_2k2_0402"
			(at 0 -1.4 180)
			(layer "B.Fab")
			(effects
				(font
					(size 0.7 0.7)
					(thickness 0.15)
				)
				(justify left bottom mirror)
			)
		)
		(property "Description" "SMD Chip Resistor, 2.2 kohm, ± 1%, 62.5 mW, 0402 [1005 Metric], Thick Film, General Purpose"
			(at 0 0 0)
			(layer "F.Fab")
			(hide yes)
			(effects
				(font
					(size 1.27 1.27)
					(thickness 0.15)
				)
			)
		)
		(property "Author" "Antmicro"
			(at 0 0 0)
			(layer "B.Fab")
			(hide yes)
			(effects
				(font
					(size 1 1)
					(thickness 0.15)
				)
				(justify mirror)
			)
		)
		(property "License" "Apache-2.0"
			(at 0 0 0)
			(layer "B.Fab")
			(hide yes)
			(effects
				(font
					(size 1 1)
					(thickness 0.15)
				)
				(justify mirror)
			)
		)
		(property "MPN" "CR0402-FX-2201GLF"
			(at 0 0 0)
			(layer "B.Fab")
			(hide yes)
			(effects
				(font
					(size 1 1)
					(thickness 0.15)
				)
				(justify mirror)
			)
		)
		(property "Manufacturer" "Bourns"
			(at 0 0 0)
			(layer "B.Fab")
			(hide yes)
			(effects
				(font
					(size 1 1)
					(thickness 0.15)
				)
				(justify mirror)
			)
		)
		(property "Tolerance" "1%"
			(at 0 0 0)
			(layer "B.Fab")
			(hide yes)
			(effects
				(font
					(size 1 1)
					(thickness 0.15)
				)
				(justify mirror)
			)
		)
		(property "Val" "2k2"
			(at 0 0 0)
			(layer "B.Fab")
			(hide yes)
			(effects
				(font
					(size 1 1)
					(thickness 0.15)
				)
				(justify mirror)
			)
		)
		(sheetname "HDMI + Ethernet")
		(sheetfile "hdmi-ethernet.kicad_sch")
		(attr smd)
		(fp_rect
			(start -0.925 0.47)
			(end 0.925 -0.47)
			(stroke
				(width 0.05)
				(type default)
			)
			(fill no)
			(layer "B.CrtYd")
		)
		(fp_rect
			(start -0.5 0.25)
			(end 0.5 -0.25)
			(stroke
				(width 0.15)
				(type solid)
			)
			(fill no)
			(layer "B.Fab")
		)
		(pad "1" smd roundrect
			(at -0.48 0)
			(size 0.59 0.64)
			(layers "B.Cu" "B.Mask" "B.Paste")
			(roundrect_rratio 0.25)
			(net 509 "/FPGA Bank 16 & 17/GBE_RGMII.RX_DV")
			(pintype "passive")
		)
		(pad "2" smd roundrect
			(at 0.48 0)
			(size 0.59 0.64)
			(layers "B.Cu" "B.Mask" "B.Paste")
			(roundrect_rratio 0.25)
			(net 1 "GND")
			(pintype "passive")
		)
	)
	(footprint "antmicro-footprints:C_0402_1005Metric"
		(layer "B.Cu")
		(at 185.05 144.999999)
		(descr "Capacitor SMD 0402")
		(tags "capacitor SMD 0402")
		(property "Reference" "C96"
			(at 1.1 1.225001 180)
			(layer "B.SilkS")
			(effects
				(font
					(size 0.7 0.7)
					(thickness 0.15)
				)
				(justify left bottom mirror)
			)
		)
		(property "Value" "C_100n_0402"
			(at 0 -1.169 180)
			(layer "B.Fab")
			(effects
				(font
					(size 0.7 0.7)
					(thickness 0.15)
				)
				(justify left bottom mirror)
			)
		)
		(property "Description" "SMD Multilayer Ceramic Capacitor, 0.1 µF, 50 V, 0402 [1005 Metric], ± 10%, X5R, GRM Series"
			(at 0 0 0)
			(layer "F.Fab")
			(hide yes)
			(effects
				(font
					(size 1.27 1.27)
					(thickness 0.15)
				)
			)
		)
		(property "Author" "Antmicro"
			(at 0 0 0)
			(layer "B.Fab")
			(hide yes)
			(effects
				(font
					(size 1 1)
					(thickness 0.15)
				)
				(justify mirror)
			)
		)
		(property "Dielectric" "X5R"
			(at 0 0 0)
			(layer "B.Fab")
			(hide yes)
			(effects
				(font
					(size 1 1)
					(thickness 0.15)
				)
				(justify mirror)
			)
		)
		(property "License" "Apache-2.0"
			(at 0 0 0)
			(layer "B.Fab")
			(hide yes)
			(effects
				(font
					(size 1 1)
					(thickness 0.15)
				)
				(justify mirror)
			)
		)
		(property "MPN" "GRM155R61H104KE14D"
			(at 0 0 0)
			(layer "B.Fab")
			(hide yes)
			(effects
				(font
					(size 1 1)
					(thickness 0.15)
				)
				(justify mirror)
			)
		)
		(property "Manufacturer" "Murata"
			(at 0 0 0)
			(layer "B.Fab")
			(hide yes)
			(effects
				(font
					(size 1 1)
					(thickness 0.15)
				)
				(justify mirror)
			)
		)
		(property "Val" "100n"
			(at 0 0 0)
			(layer "B.Fab")
			(hide yes)
			(effects
				(font
					(size 1 1)
					(thickness 0.15)
				)
				(justify mirror)
			)
		)
		(property "Voltage" "50V"
			(at 0 0 0)
			(layer "B.Fab")
			(hide yes)
			(effects
				(font
					(size 1 1)
					(thickness 0.15)
				)
				(justify mirror)
			)
		)
		(sheetname "FPGA Bank 33 & 34")
		(sheetfile "fpga-bank-33-34.kicad_sch")
		(attr smd)
		(fp_rect
			(start -0.925 0.47)
			(end 0.925 -0.47)
			(stroke
				(width 0.05)
				(type default)
			)
			(fill no)
			(layer "B.CrtYd")
		)
		(fp_line
			(start -0.494 -0.248)
			(end -0.494 0.25)
			(stroke
				(width 0.15)
				(type solid)
			)
			(layer "B.Fab")
		)
		(fp_line
			(start -0.494 0.25)
			(end 0.504 0.25)
			(stroke
				(width 0.15)
				(type solid)
			)
			(layer "B.Fab")
		)
		(fp_line
			(start 0.504 -0.248)
			(end -0.494 -0.248)
			(stroke
				(width 0.15)
				(type solid)
			)
			(layer "B.Fab")
		)
		(fp_line
			(start 0.504 0.25)
			(end 0.504 -0.248)
			(stroke
				(width 0.15)
				(type solid)
			)
			(layer "B.Fab")
		)
		(pad "1" smd roundrect
			(at -0.48 0)
			(size 0.59 0.64)
			(layers "B.Cu" "B.Mask" "B.Paste")
			(roundrect_rratio 0.25)
			(net 1 "GND")
			(pintype "passive")
		)
		(pad "2" smd roundrect
			(at 0.48 0)
			(size 0.59 0.64)
			(layers "B.Cu" "B.Mask" "B.Paste")
			(roundrect_rratio 0.25)
			(net 25 "+1V35")
			(pintype "passive")
		)
	)
)
